# S9S_MB_2U (Grand Teton) — schematic netlist excerpt (pin names and nets, part order shuffled) for the footprints in the layout excerpt that follows; sources: Cadence DE-HDL packaged netlist, KiCad conversion of 03242023_DA0F0TMBIJ0_F0T_Motherboard_J_brd_V01_OCP.brd

ME9  ME_DUMMY_SYMBOL  PICKUP_SMDC20 EMPTY  pkg PICKUP_SMDC20  page 312
R361  Q_RES  1K 1% CHIP  pkg 0402LF  page 278 : A = P3V3_AUX ; B = PWRGD_PVCCD_HV_CPU0_R
PR1410  Q_RES  49.9 1% CHIP  pkg 0402LF  page 296 : A = P12V_AUX_CPU1_DIMM_ISEN_N ; B = PVCCD_HV_CPU1_ISENSE_N

(kicad_pcb
	(version 20260206)
	(generator "pcbnew")
	(generator_version "10.0")
	(general
		(thickness 1.6)
		(legacy_teardrops no)
	)
	(paper "A4")
	(title_block
		(title "03242023_DA0F0TMBIJ0_F0T_Motherboard_J_brd_V01_OCP.brd")
		(comment 1 "Grand Teton / footprints 5861-5863 of 6105")
	)
	(layers
		(0 "F.Cu" signal "TOP")
		(4 "In1.Cu" signal "GND")
		(6 "In2.Cu" signal "IN1")
		(8 "In3.Cu" signal "GND1")
		(10 "In4.Cu" signal "IN2")
		(12 "In5.Cu" signal "GND2")
		(14 "In6.Cu" signal "IN3")
		(16 "In7.Cu" signal "GND3")
		(18 "In8.Cu" signal "VCC")
		(20 "In9.Cu" signal "VCC1")
		(22 "In10.Cu" signal "GND4")
		(24 "In11.Cu" signal "IN4")
		(26 "In12.Cu" signal "GND5")
		(28 "In13.Cu" signal "IN5")
		(30 "In14.Cu" signal "GND6")
		(32 "In15.Cu" signal "IN6")
		(34 "In16.Cu" signal "GND7")
		(2 "B.Cu" signal "BOTTOM")
		(9 "F.Adhes" user "F.Adhesive")
		(11 "B.Adhes" user "B.Adhesive")
		(13 "F.Paste" user "Package Geometry/Pastemask Top")
		(15 "B.Paste" user "Package Geometry/Pastemask Bottom")
		(5 "F.SilkS" user "Ref Des/Silkscreen Top")
		(7 "B.SilkS" user "Ref Des/Silkscreen Bottom")
		(1 "F.Mask" user "Board Geometry/Soldermask Top")
		(3 "B.Mask" user "Board Geometry/Soldermask Bottom")
		(17 "Dwgs.User" user "User.Drawings")
		(19 "Cmts.User" user "User.Comments")
		(21 "Eco1.User" user "User.Eco1")
		(23 "Eco2.User" user "User.Eco2")
		(25 "Edge.Cuts" user "Board Geometry/Outline")
		(27 "Margin" user)
		(31 "F.CrtYd" user "Package Geometry/Place Bound Top")
		(29 "B.CrtYd" user "Package Geometry/Place Bound Bottom")
		(35 "F.Fab" user "Ref Des/Assembly Top")
		(33 "B.Fab" user "Ref Des/Assembly Bottom")
	)
	(footprint ""
		(layer "B.Cu")
		(at 34.846514 -166.733474)
		(property "Reference" "PR1410"
			(at 0 0 0)
			(layer "B.SilkS")
			(hide yes)
			(effects
				(font
					(size 1.27 1.27)
				)
				(justify mirror)
			)
		)
		(property "Value" ""
			(at 0 0 0)
			(layer "B.Fab")
			(effects
				(font
					(size 1.27 1.27)
				)
				(justify mirror)
			)
		)
		(duplicate_pad_numbers_are_jumpers no)
		(fp_line
			(start -0.7874 -0.4064)
			(end -0.7874 0.4064)
			(stroke
				(width 0.1524)
				(type default)
			)
			(layer "B.SilkS")
		)
		(fp_line
			(start -0.7874 0.4064)
			(end 0.7874 0.4064)
			(stroke
				(width 0.1524)
				(type default)
			)
			(layer "B.SilkS")
		)
		(fp_line
			(start 0.7874 -0.4064)
			(end -0.7874 -0.4064)
			(stroke
				(width 0.1524)
				(type default)
			)
			(layer "B.SilkS")
		)
		(fp_line
			(start 0.7874 0.4064)
			(end 0.7874 -0.4064)
			(stroke
				(width 0.1524)
				(type default)
			)
			(layer "B.SilkS")
		)
		(fp_line
			(start -0.67945 -0.3048)
			(end -0.67945 0.3048)
			(stroke
				(width 0.1)
				(type default)
			)
			(layer "B.Fab")
		)
		(fp_line
			(start -0.67945 0.3048)
			(end -0.120396 0.3048)
			(stroke
				(width 0.1)
				(type default)
			)
			(layer "B.Fab")
		)
		(fp_line
			(start -0.12065 -0.3048)
			(end -0.67945 -0.3048)
			(stroke
				(width 0.1)
				(type default)
			)
			(layer "B.Fab")
		)
		(fp_line
			(start -0.12065 -0.2794)
			(end -0.12065 -0.3048)
			(stroke
				(width 0.1)
				(type default)
			)
			(layer "B.Fab")
		)
		(fp_line
			(start -0.120396 0.2794)
			(end 0.12065 0.2794)
			(stroke
				(width 0.1)
				(type default)
			)
			(layer "B.Fab")
		)
		(fp_line
			(start -0.120396 0.3048)
			(end -0.120396 0.2794)
			(stroke
				(width 0.1)
				(type default)
			)
			(layer "B.Fab")
		)
		(fp_line
			(start 0.12065 -0.305054)
			(end 0.12065 -0.2794)
			(stroke
				(width 0.1)
				(type default)
			)
			(layer "B.Fab")
		)
		(fp_line
			(start 0.12065 -0.2794)
			(end -0.12065 -0.2794)
			(stroke
				(width 0.1)
				(type default)
			)
			(layer "B.Fab")
		)
		(fp_line
			(start 0.12065 0.2794)
			(end 0.12065 0.3048)
			(stroke
				(width 0.1)
				(type default)
			)
			(layer "B.Fab")
		)
		(fp_line
			(start 0.12065 0.3048)
			(end 0.67945 0.3048)
			(stroke
				(width 0.1)
				(type default)
			)
			(layer "B.Fab")
		)
		(fp_line
			(start 0.67945 -0.305054)
			(end 0.12065 -0.305054)
			(stroke
				(width 0.1)
				(type default)
			)
			(layer "B.Fab")
		)
		(fp_line
			(start 0.67945 0.3048)
			(end 0.67945 -0.305054)
			(stroke
				(width 0.1)
				(type default)
			)
			(layer "B.Fab")
		)
		(pad "1" smd circle
			(at 0.40005 0 180)
			(size 0 0)
			(layers "B.Cu" "B.Mask" "B.Paste")
			(net "P12V_AUX_CPU1_DIMM_ISEN_N")
		)
		(pad "2" smd circle
			(at -0.40005 0 180)
			(size 0 0)
			(layers "B.Cu" "B.Mask" "B.Paste")
			(net "PVCCD_HV_CPU1_ISENSE_N")
		)
	)
	(footprint ""
		(layer "B.Cu")
		(at 436.971694 -119.952008)
		(property "Reference" "R361"
			(at 0 0 0)
			(layer "B.SilkS")
			(hide yes)
			(effects
				(font
					(size 1.27 1.27)
				)
				(justify mirror)
			)
		)
		(property "Value" ""
			(at 0 0 0)
			(layer "B.Fab")
			(effects
				(font
					(size 1.27 1.27)
				)
				(justify mirror)
			)
		)
		(duplicate_pad_numbers_are_jumpers no)
		(fp_line
			(start -0.7874 -0.4064)
			(end -0.7874 0.4064)
			(stroke
				(width 0.1524)
				(type default)
			)
			(layer "B.SilkS")
		)
		(fp_line
			(start -0.7874 0.4064)
			(end 0.7874 0.4064)
			(stroke
				(width 0.1524)
				(type default)
			)
			(layer "B.SilkS")
		)
		(fp_line
			(start 0.7874 -0.4064)
			(end -0.7874 -0.4064)
			(stroke
				(width 0.1524)
				(type default)
			)
			(layer "B.SilkS")
		)
		(fp_line
			(start 0.7874 0.4064)
			(end 0.7874 -0.4064)
			(stroke
				(width 0.1524)
				(type default)
			)
			(layer "B.SilkS")
		)
		(fp_line
			(start -0.67945 -0.3048)
			(end -0.67945 0.3048)
			(stroke
				(width 0.1)
				(type default)
			)
			(layer "B.Fab")
		)
		(fp_line
			(start -0.67945 0.3048)
			(end -0.120396 0.3048)
			(stroke
				(width 0.1)
				(type default)
			)
			(layer "B.Fab")
		)
		(fp_line
			(start -0.12065 -0.3048)
			(end -0.67945 -0.3048)
			(stroke
				(width 0.1)
				(type default)
			)
			(layer "B.Fab")
		)
		(fp_line
			(start -0.12065 -0.2794)
			(end -0.12065 -0.3048)
			(stroke
				(width 0.1)
				(type default)
			)
			(layer "B.Fab")
		)
		(fp_line
			(start -0.120396 0.2794)
			(end 0.12065 0.2794)
			(stroke
				(width 0.1)
				(type default)
			)
			(layer "B.Fab")
		)
		(fp_line
			(start -0.120396 0.3048)
			(end -0.120396 0.2794)
			(stroke
				(width 0.1)
				(type default)
			)
			(layer "B.Fab")
		)
		(fp_line
			(start 0.12065 -0.305054)
			(end 0.12065 -0.2794)
			(stroke
				(width 0.1)
				(type default)
			)
			(layer "B.Fab")
		)
		(fp_line
			(start 0.12065 -0.2794)
			(end -0.12065 -0.2794)
			(stroke
				(width 0.1)
				(type default)
			)
			(layer "B.Fab")
		)
		(fp_line
			(start 0.12065 0.2794)
			(end 0.12065 0.3048)
			(stroke
				(width 0.1)
				(type default)
			)
			(layer "B.Fab")
		)
		(fp_line
			(start 0.12065 0.3048)
			(end 0.67945 0.3048)
			(stroke
				(width 0.1)
				(type default)
			)
			(layer "B.Fab")
		)
		(fp_line
			(start 0.67945 -0.305054)
			(end 0.12065 -0.305054)
			(stroke
				(width 0.1)
				(type default)
			)
			(layer "B.Fab")
		)
		(fp_line
			(start 0.67945 0.3048)
			(end 0.67945 -0.305054)
			(stroke
				(width 0.1)
				(type default)
			)
			(layer "B.Fab")
		)
		(pad "1" smd circle
			(at 0.40005 0 180)
			(size 0 0)
			(layers "B.Cu" "B.Mask" "B.Paste")
			(net "P3V3_AUX")
		)
		(pad "2" smd circle
			(at -0.40005 0 180)
			(size 0 0)
			(layers "B.Cu" "B.Mask" "B.Paste")
			(net "PWRGD_PVCCD_HV_CPU0_R")
		)
	)
	(footprint ""
		(layer "B.Cu")
		(at 65.55994 -379.0696)
		(property "Reference" "ME9"
			(at 9.652 -9.540748 0)
			(unlocked yes)
			(layer "B.SilkS")
			(effects
				(font
					(size 0.7874 0.5842)
					(thickness 0.1524)
				)
				(justify left mirror)
			)
		)
		(property "Value" ""
			(at 0 0 0)
			(layer "B.Fab")
			(effects
				(font
					(size 1.27 1.27)
				)
				(justify mirror)
			)
		)
		(duplicate_pad_numbers_are_jumpers no)
		(zone
			(layer "B.Cu")
			(hatch none 0.5)
			(connect_pads
				(clearance 0)
			)
			(min_thickness 0.25)
			(keepout
				(tracks allowed)
				(vias allowed)
				(pads allowed)
				(copperpour allowed)
				(footprints not_allowed)
			)
			(placement
				(enabled no)
				(sheetname "")
			)
			(fill
				(thermal_gap 0.5)
				(thermal_bridge_width 0.5)
				(island_removal_mode 0)
			)
			(polygon
				(pts
					(arc
						(start 75.55992 -379.0696)
						(mid 55.55996 -379.0696)
						(end 75.55992 -379.0696)
					)
				)
			)
		)
	)
)
